# T6G (Grand Teton) — schematic netlist excerpt (pin names and nets, part order shuffled) for the footprints in the layout excerpt that follows; sources: Cadence DE-HDL packaged netlist, KiCad conversion of 04192023_DAF0TMB3IC0_F0TG_MB_C_brd_V02_OCP.brd

C2116  Q_CAP  22UF 4V 20% X6S  pkg C0402  page 74 : A = PVDDIO_P1 ; B = GND
C430  Q_CAP  0.1UF 10V 10% X7S  pkg C0201  page 345 : A = P0V9_CPU1_RT2_2A ; B = GND
C1240  Q_CAP  0.1UF 25V 10% X7R  pkg 0402  page 131 : A = P3V3_OCP_SFF ; B = GND

(kicad_pcb
	(version 20260206)
	(generator "pcbnew")
	(generator_version "10.0")
	(general
		(thickness 1.6)
		(legacy_teardrops no)
	)
	(paper "A4")
	(title_block
		(title "04192023_DAF0TMB3IC0_F0TG_MB_C_brd_V02_OCP.brd")
		(comment 1 "Grand Teton / footprints 7043-7045 of 8354")
	)
	(layers
		(0 "F.Cu" signal "TOP")
		(4 "In1.Cu" signal "GND")
		(6 "In2.Cu" signal "IN1")
		(8 "In3.Cu" signal "GND1")
		(10 "In4.Cu" signal "IN2")
		(12 "In5.Cu" signal "GND2")
		(14 "In6.Cu" signal "IN3")
		(16 "In7.Cu" signal "GND3")
		(18 "In8.Cu" signal "VCC")
		(20 "In9.Cu" signal "VCC1")
		(22 "In10.Cu" signal "GND4")
		(24 "In11.Cu" signal "IN4")
		(26 "In12.Cu" signal "GND5")
		(28 "In13.Cu" signal "IN5")
		(30 "In14.Cu" signal "GND6")
		(32 "In15.Cu" signal "IN6")
		(34 "In16.Cu" signal "GND7")
		(2 "B.Cu" signal "BOTTOM")
		(9 "F.Adhes" user "F.Adhesive")
		(11 "B.Adhes" user "B.Adhesive")
		(13 "F.Paste" user "Package Geometry/Pastemask Top")
		(15 "B.Paste" user "Package Geometry/Pastemask Bottom")
		(5 "F.SilkS" user "Ref Des/Silkscreen Top")
		(7 "B.SilkS" user "Ref Des/Silkscreen Bottom")
		(1 "F.Mask" user "Board Geometry/Soldermask Top")
		(3 "B.Mask" user "Board Geometry/Soldermask Bottom")
		(17 "Dwgs.User" user "User.Drawings")
		(19 "Cmts.User" user "User.Comments")
		(21 "Eco1.User" user "User.Eco1")
		(23 "Eco2.User" user "User.Eco2")
		(25 "Edge.Cuts" user "Board Geometry/Outline")
		(27 "Margin" user)
		(31 "F.CrtYd" user "Package Geometry/Place Bound Top")
		(29 "B.CrtYd" user "Package Geometry/Place Bound Bottom")
		(35 "F.Fab" user "Ref Des/Assembly Top")
		(33 "B.Fab" user "Ref Des/Assembly Bottom")
	)
	(footprint ""
		(layer "B.Cu")
		(at 98.493834 -261.947152)
		(property "Reference" "C2116"
			(at 0 0 0)
			(layer "B.SilkS")
			(hide yes)
			(effects
				(font
					(size 1.27 1.27)
				)
				(justify mirror)
			)
		)
		(property "Value" ""
			(at 0 0 0)
			(layer "B.Fab")
			(effects
				(font
					(size 1.27 1.27)
				)
				(justify mirror)
			)
		)
		(duplicate_pad_numbers_are_jumpers no)
		(fp_line
			(start -0.7874 -0.4064)
			(end -0.7874 0.4064)
			(stroke
				(width 0.1524)
				(type default)
			)
			(layer "B.SilkS")
		)
		(fp_line
			(start -0.7874 0.4064)
			(end 0.7874 0.4064)
			(stroke
				(width 0.1524)
				(type default)
			)
			(layer "B.SilkS")
		)
		(fp_line
			(start 0.7874 -0.4064)
			(end -0.7874 -0.4064)
			(stroke
				(width 0.1524)
				(type default)
			)
			(layer "B.SilkS")
		)
		(fp_line
			(start 0.7874 0.4064)
			(end 0.7874 -0.4064)
			(stroke
				(width 0.1524)
				(type default)
			)
			(layer "B.SilkS")
		)
		(fp_line
			(start -0.67945 -0.3048)
			(end -0.67945 0.3048)
			(stroke
				(width 0.1)
				(type default)
			)
			(layer "B.Fab")
		)
		(fp_line
			(start -0.67945 0.3048)
			(end -0.120396 0.3048)
			(stroke
				(width 0.1)
				(type default)
			)
			(layer "B.Fab")
		)
		(fp_line
			(start -0.12065 -0.3048)
			(end -0.67945 -0.3048)
			(stroke
				(width 0.1)
				(type default)
			)
			(layer "B.Fab")
		)
		(fp_line
			(start -0.12065 -0.2794)
			(end -0.12065 -0.3048)
			(stroke
				(width 0.1)
				(type default)
			)
			(layer "B.Fab")
		)
		(fp_line
			(start -0.120396 0.2794)
			(end 0.12065 0.2794)
			(stroke
				(width 0.1)
				(type default)
			)
			(layer "B.Fab")
		)
		(fp_line
			(start -0.120396 0.3048)
			(end -0.120396 0.2794)
			(stroke
				(width 0.1)
				(type default)
			)
			(layer "B.Fab")
		)
		(fp_line
			(start 0.12065 -0.305054)
			(end 0.12065 -0.2794)
			(stroke
				(width 0.1)
				(type default)
			)
			(layer "B.Fab")
		)
		(fp_line
			(start 0.12065 -0.2794)
			(end -0.12065 -0.2794)
			(stroke
				(width 0.1)
				(type default)
			)
			(layer "B.Fab")
		)
		(fp_line
			(start 0.12065 0.2794)
			(end 0.12065 0.3048)
			(stroke
				(width 0.1)
				(type default)
			)
			(layer "B.Fab")
		)
		(fp_line
			(start 0.12065 0.3048)
			(end 0.67945 0.3048)
			(stroke
				(width 0.1)
				(type default)
			)
			(layer "B.Fab")
		)
		(fp_line
			(start 0.67945 -0.305054)
			(end 0.12065 -0.305054)
			(stroke
				(width 0.1)
				(type default)
			)
			(layer "B.Fab")
		)
		(fp_line
			(start 0.67945 0.3048)
			(end 0.67945 -0.305054)
			(stroke
				(width 0.1)
				(type default)
			)
			(layer "B.Fab")
		)
		(pad "1" smd circle
			(at 0.40005 0 180)
			(size 0 0)
			(layers "B.Cu" "B.Mask" "B.Paste")
			(net "PVDDIO_P1")
		)
		(pad "2" smd circle
			(at -0.40005 0 180)
			(size 0 0)
			(layers "B.Cu" "B.Mask" "B.Paste")
			(net "GND")
		)
	)
	(footprint ""
		(layer "B.Cu")
		(at 163.946332 -388.011162 -90)
		(property "Reference" "C430"
			(at 0 0 90)
			(layer "B.SilkS")
			(hide yes)
			(effects
				(font
					(size 1.27 1.27)
				)
				(justify mirror)
			)
		)
		(property "Value" ""
			(at 0 0 90)
			(layer "B.Fab")
			(effects
				(font
					(size 1.27 1.27)
				)
				(justify mirror)
			)
		)
		(duplicate_pad_numbers_are_jumpers no)
		(fp_line
			(start -0.299974 0.150114)
			(end 0.299974 0.150114)
			(stroke
				(width 0.1)
				(type default)
			)
			(layer "B.Fab")
		)
		(fp_line
			(start 0.299974 0.150114)
			(end 0.299974 -0.150114)
			(stroke
				(width 0.1)
				(type default)
			)
			(layer "B.Fab")
		)
		(fp_line
			(start -0.299974 -0.150114)
			(end -0.299974 0.150114)
			(stroke
				(width 0.1)
				(type default)
			)
			(layer "B.Fab")
		)
		(fp_line
			(start 0.299974 -0.150114)
			(end -0.299974 -0.150114)
			(stroke
				(width 0.1)
				(type default)
			)
			(layer "B.Fab")
		)
		(pad "1" smd rect
			(at 0.2667 0 90)
			(size 0.3048 0.381)
			(layers "B.Cu" "B.Mask" "B.Paste")
			(net "P0V9_CPU1_RT2_2A")
		)
		(pad "2" smd rect
			(at -0.2667 0 90)
			(size 0.3048 0.381)
			(layers "B.Cu" "B.Mask" "B.Paste")
			(net "GND")
		)
	)
	(footprint ""
		(layer "B.Cu")
		(at 435.549802 -10.072116 180)
		(property "Reference" "C1240"
			(at 0 0 0)
			(layer "B.SilkS")
			(hide yes)
			(effects
				(font
					(size 1.27 1.27)
				)
				(justify mirror)
			)
		)
		(property "Value" ""
			(at 0 0 0)
			(layer "B.Fab")
			(effects
				(font
					(size 1.27 1.27)
				)
				(justify mirror)
			)
		)
		(duplicate_pad_numbers_are_jumpers no)
		(fp_line
			(start 0.7874 0.4064)
			(end 0.7874 -0.4064)
			(stroke
				(width 0.1524)
				(type default)
			)
			(layer "B.SilkS")
		)
		(fp_line
			(start 0.7874 -0.4064)
			(end -0.7874 -0.4064)
			(stroke
				(width 0.1524)
				(type default)
			)
			(layer "B.SilkS")
		)
		(fp_line
			(start -0.7874 0.4064)
			(end 0.7874 0.4064)
			(stroke
				(width 0.1524)
				(type default)
			)
			(layer "B.SilkS")
		)
		(fp_line
			(start -0.7874 -0.4064)
			(end -0.7874 0.4064)
			(stroke
				(width 0.1524)
				(type default)
			)
			(layer "B.SilkS")
		)
		(fp_line
			(start 0.67945 0.3048)
			(end 0.67945 -0.305054)
			(stroke
				(width 0.1)
				(type default)
			)
			(layer "B.Fab")
		)
		(fp_line
			(start 0.67945 -0.305054)
			(end 0.12065 -0.305054)
			(stroke
				(width 0.1)
				(type default)
			)
			(layer "B.Fab")
		)
		(fp_line
			(start 0.12065 0.3048)
			(end 0.67945 0.3048)
			(stroke
				(width 0.1)
				(type default)
			)
			(layer "B.Fab")
		)
		(fp_line
			(start 0.12065 0.2794)
			(end 0.12065 0.3048)
			(stroke
				(width 0.1)
				(type default)
			)
			(layer "B.Fab")
		)
		(fp_line
			(start 0.12065 -0.2794)
			(end -0.12065 -0.2794)
			(stroke
				(width 0.1)
				(type default)
			)
			(layer "B.Fab")
		)
		(fp_line
			(start 0.12065 -0.305054)
			(end 0.12065 -0.2794)
			(stroke
				(width 0.1)
				(type default)
			)
			(layer "B.Fab")
		)
		(fp_line
			(start -0.120396 0.3048)
			(end -0.120396 0.2794)
			(stroke
				(width 0.1)
				(type default)
			)
			(layer "B.Fab")
		)
		(fp_line
			(start -0.120396 0.2794)
			(end 0.12065 0.2794)
			(stroke
				(width 0.1)
				(type default)
			)
			(layer "B.Fab")
		)
		(fp_line
			(start -0.12065 -0.2794)
			(end -0.12065 -0.3048)
			(stroke
				(width 0.1)
				(type default)
			)
			(layer "B.Fab")
		)
		(fp_line
			(start -0.12065 -0.3048)
			(end -0.67945 -0.3048)
			(stroke
				(width 0.1)
				(type default)
			)
			(layer "B.Fab")
		)
		(fp_line
			(start -0.67945 0.3048)
			(end -0.120396 0.3048)
			(stroke
				(width 0.1)
				(type default)
			)
			(layer "B.Fab")
		)
		(fp_line
			(start -0.67945 -0.3048)
			(end -0.67945 0.3048)
			(stroke
				(width 0.1)
				(type default)
			)
			(layer "B.Fab")
		)
		(pad "1" smd circle
			(at 0.40005 0)
			(size 0 0)
			(layers "B.Cu" "B.Mask" "B.Paste")
			(net "P3V3_OCP_SFF")
		)
		(pad "2" smd circle
			(at -0.40005 0)
			(size 0 0)
			(layers "B.Cu" "B.Mask" "B.Paste")
			(net "GND")
		)
	)
)
